(kicad_pcb
	(version 20241229)
	(generator "pcbnew")
	(generator_version "9.0")
	(general
		(thickness 1.61)
		(legacy_teardrops no)
	)
	(paper "A3")
	(title_block
		(title "SO-DIMM DDR5 Tester")
		(date "2025-11-26")
		(rev "1.3.0")
		(comment 9 "footprints 157-163 of 627")
	)
	(layers
		(0 "F.Cu" signal)
		(4 "In1.Cu" power)
		(6 "In2.Cu" mixed)
		(8 "In3.Cu" power)
		(10 "In4.Cu" mixed)
		(12 "In5.Cu" power)
		(14 "In6.Cu" mixed)
		(16 "In7.Cu" power)
		(18 "In8.Cu" power)
		(20 "In9.Cu" mixed)
		(22 "In10.Cu" power)
		(2 "B.Cu" signal)
		(9 "F.Adhes" user "F.Adhesive")
		(11 "B.Adhes" user "B.Adhesive")
		(13 "F.Paste" user)
		(15 "B.Paste" user)
		(5 "F.SilkS" user "F.Silkscreen")
		(7 "B.SilkS" user "B.Silkscreen")
		(1 "F.Mask" user)
		(3 "B.Mask" user)
		(17 "Dwgs.User" user "User.Drawings")
		(19 "Cmts.User" user "User.Comments")
		(21 "Eco1.User" user "User.Eco1")
		(23 "Eco2.User" user "User.Eco2")
		(25 "Edge.Cuts" user)
		(27 "Margin" user)
		(31 "F.CrtYd" user "F.Courtyard")
		(29 "B.CrtYd" user "B.Courtyard")
		(35 "F.Fab" user)
		(33 "B.Fab" user)
	)
	(footprint "antmicro-footprints:TP_SMD_1mm"
		(layer "F.Cu")
		(at 186.4 190.85)
		(property "Reference" "TP18"
			(at 0 -0.731898 0)
			(layer "F.SilkS")
			(hide yes)
			(effects
				(font
					(size 0.7 0.7)
					(thickness 0.15)
				)
				(justify left bottom)
			)
		)
		(property "Value" "TP_1mm_SMD"
			(at 0 1.4 0)
			(layer "F.Fab")
			(effects
				(font
					(size 0.7 0.7)
					(thickness 0.15)
				)
				(justify left bottom)
			)
		)
		(property "Author" "Antmicro"
			(at 0 0 0)
			(layer "F.Fab")
			(hide yes)
			(effects
				(font
					(size 1 1)
					(thickness 0.15)
				)
			)
		)
		(property "License" "Apache-2.0"
			(at 0 0 0)
			(layer "F.Fab")
			(hide yes)
			(effects
				(font
					(size 1 1)
					(thickness 0.15)
				)
			)
		)
		(property "MPN" ""
			(at 0 0 0)
			(layer "F.Fab")
			(hide yes)
			(effects
				(font
					(size 1 1)
					(thickness 0.15)
				)
			)
		)
		(property "Manufacturer" ""
			(at 0 0 0)
			(layer "F.Fab")
			(hide yes)
			(effects
				(font
					(size 1 1)
					(thickness 0.15)
				)
			)
		)
		(sheetname "/Supply/")
		(sheetfile "supply.kicad_sch")
		(attr exclude_from_pos_files)
		(pad "1" smd circle
			(at 0 0)
			(size 1 1)
			(layers "F.Cu" "F.Mask")
			(net 64 "/Supply/1V7")
			(pinfunction "1")
			(pintype "passive")
		)
	)
	(footprint "antmicro-footprints:DFN-6-1EP_2x2mm_P0.65mm_EP1x1.6mm"
		(layer "F.Cu")
		(at 182.541 151.875 90)
		(descr "6-Lead Plastic Dual Flat, No Lead Package - 2x2x0.9 mm Body")
		(tags "DFN")
		(property "Reference" "U29"
			(at -1.025 2.159 90)
			(layer "F.SilkS")
			(effects
				(font
					(size 0.7 0.7)
					(thickness 0.15)
				)
				(justify left bottom)
			)
		)
		(property "Value" "MCP4726A0T_DFN"
			(at 0 2.1 90)
			(layer "F.Fab")
			(effects
				(font
					(size 0.7 0.7)
					(thickness 0.15)
				)
				(justify left bottom)
			)
		)
		(property "Datasheet" "https://ww1.microchip.com/downloads/en/DeviceDoc/22272C.pdf"
			(at 0 0 90)
			(layer "F.Fab")
			(hide yes)
			(effects
				(font
					(size 1.27 1.27)
					(thickness 0.15)
				)
			)
		)
		(property "Author" "Antmicro"
			(at 334.416 -30.666 0)
			(layer "F.Fab")
			(hide yes)
			(effects
				(font
					(size 1 1)
					(thickness 0.15)
				)
			)
		)
		(property "License" "Apache-2.0"
			(at 334.416 -30.666 0)
			(layer "F.Fab")
			(hide yes)
			(effects
				(font
					(size 1 1)
					(thickness 0.15)
				)
			)
		)
		(property "MPN" "MCP4726A0T-E/MAY"
			(at 334.416 -30.666 0)
			(layer "F.Fab")
			(hide yes)
			(effects
				(font
					(size 1 1)
					(thickness 0.15)
				)
			)
		)
		(property "Manufacturer" "Microchip Technology"
			(at 334.416 -30.666 0)
			(layer "F.Fab")
			(hide yes)
			(effects
				(font
					(size 1 1)
					(thickness 0.15)
				)
			)
		)
		(property ki_fp_filters "DFN6_2x2MC_MCH DFN6_2x2MC_MCH-M DFN6_2x2MC_MCH-L")
		(sheetname "/Supply/")
		(sheetfile "supply.kicad_sch")
		(attr smd)
		(fp_line
			(start 1.075 -1.1)
			(end 1.075 -0.925)
			(stroke
				(width 0.15)
				(type solid)
			)
			(layer "F.SilkS")
		)
		(fp_line
			(start -1.075 -1.1)
			(end 1.075 -1.1)
			(stroke
				(width 0.15)
				(type solid)
			)
			(layer "F.SilkS")
		)
		(fp_line
			(start -1.075 -1.1)
			(end -1.075 -0.925)
			(stroke
				(width 0.15)
				(type solid)
			)
			(layer "F.SilkS")
		)
		(fp_line
			(start 1.075 0.9375)
			(end 1.075 1.1125)
			(stroke
				(width 0.15)
				(type solid)
			)
			(layer "F.SilkS")
		)
		(fp_line
			(start -1.075 0.9375)
			(end -1.075 1.1125)
			(stroke
				(width 0.15)
				(type solid)
			)
			(layer "F.SilkS")
		)
		(fp_line
			(start -1.075 1.1125)
			(end 1.075 1.1125)
			(stroke
				(width 0.15)
				(type solid)
			)
			(layer "F.SilkS")
		)
		(fp_circle
			(center -1.325 -1.04571)
			(end -1.275 -1.04571)
			(stroke
				(width 0.15)
				(type solid)
			)
			(fill yes)
			(layer "F.SilkS")
		)
		(fp_rect
			(start -1.405 -1.25)
			(end 1.405 1.225)
			(stroke
				(width 0.05)
				(type solid)
			)
			(fill no)
			(layer "F.CrtYd")
		)
		(fp_line
			(start -1 -0.5)
			(end -0.5 -1)
			(stroke
				(width 0.15)
				(type solid)
			)
			(layer "F.Fab")
		)
		(fp_rect
			(start 1 1)
			(end -1 -1)
			(stroke
				(width 0.15)
				(type solid)
			)
			(fill no)
			(layer "F.Fab")
		)
		(pad "" smd rect
			(at 0 -0.402 90)
			(size 0.82 0.63)
			(layers "F.Paste")
		)
		(pad "" smd rect
			(at 0 0.4 90)
			(size 0.82 0.63)
			(layers "F.Paste")
		)
		(pad "1" smd rect
			(at -1.051 -0.652 90)
			(size 0.65 0.35)
			(layers "F.Cu" "F.Mask" "F.Paste")
			(net 206 "+1V1")
			(pinfunction "VREF")
			(pintype "power_in")
		)
		(pad "2" smd rect
			(at -1.051 0 90)
			(size 0.65 0.35)
			(layers "F.Cu" "F.Mask" "F.Paste")
			(net 297 "/Supply/PWR_SCL_2")
			(pinfunction "SCL")
			(pintype "input")
		)
		(pad "3" smd rect
			(at -1.051 0.65 90)
			(size 0.65 0.35)
			(layers "F.Cu" "F.Mask" "F.Paste")
			(net 298 "/Supply/PWR_SDA_2")
			(pinfunction "SDA")
			(pintype "bidirectional")
		)
		(pad "4" smd rect
			(at 1.05 0.65 90)
			(size 0.65 0.35)
			(layers "F.Cu" "F.Mask" "F.Paste")
			(net 200 "+3V3")
			(pinfunction "VDD")
			(pintype "power_in")
		)
		(pad "5" smd rect
			(at 1.05 0 90)
			(size 0.65 0.35)
			(layers "F.Cu" "F.Mask" "F.Paste")
			(net 1 "GND")
			(pinfunction "GND")
			(pintype "power_in")
		)
		(pad "6" smd rect
			(at 1.05 -0.652 90)
			(size 0.65 0.35)
			(layers "F.Cu" "F.Mask" "F.Paste")
			(net 36 "DAC_VREF")
			(pinfunction "VOUT")
			(pintype "output")
		)
		(pad "7" smd rect
			(at 0 0 90)
			(size 1 1.6)
			(layers "F.Cu" "F.Mask")
			(net 1 "GND")
			(pinfunction "SH")
			(pintype "power_in")
		)
	)
	(footprint "antmicro-footprints:MP_Pad6mm_Drill3mm"
		(layer "F.Cu")
		(at 76.375501 119.551)
		(property "Reference" "MP1"
			(at 0 -3.2 0)
			(layer "F.SilkS")
			(hide yes)
			(effects
				(font
					(size 0.7 0.7)
					(thickness 0.15)
				)
				(justify left bottom)
			)
		)
		(property "Value" "MP_Pad6mm_Drill3mm"
			(at 0 3.9 0)
			(layer "F.Fab")
			(effects
				(font
					(size 0.7 0.7)
					(thickness 0.15)
				)
				(justify left bottom)
			)
		)
		(attr board_only exclude_from_pos_files exclude_from_bom)
		(pad "1" thru_hole circle
			(at 0 0)
			(size 6 6)
			(drill 3)
			(layers "*.Cu" "*.Mask")
			(remove_unused_layers no)
			(net 1 "GND")
		)
	)
	(footprint "antmicro-footprints:NetTie-2_SMD_Pad0.127mm"
		(layer "F.Cu")
		(at 198.175 191.326 180)
		(descr "Net tie, 2 pin, 0.127mm  SMD pads")
		(tags "net tie")
		(property "Reference" "NT12"
			(at -0.128 -1.345 180)
			(layer "F.SilkS")
			(hide yes)
			(effects
				(font
					(size 0.7 0.7)
					(thickness 0.15)
				)
				(justify left bottom)
			)
		)
		(property "Value" "Net-Tie_P0.127mm"
			(at 0 1.199 180)
			(layer "F.Fab")
			(effects
				(font
					(size 0.7 0.7)
					(thickness 0.15)
				)
				(justify left bottom)
			)
		)
		(property "Author" "Antmicro"
			(at 396.35 382.652 0)
			(layer "F.Fab")
			(hide yes)
			(effects
				(font
					(size 1 1)
					(thickness 0.15)
				)
			)
		)
		(property "License" "Apache-2.0"
			(at 396.35 382.652 0)
			(layer "F.Fab")
			(hide yes)
			(effects
				(font
					(size 1 1)
					(thickness 0.15)
				)
			)
		)
		(property "MPN" ""
			(at 396.35 382.652 0)
			(layer "F.Fab")
			(hide yes)
			(effects
				(font
					(size 1 1)
					(thickness 0.15)
				)
			)
		)
		(property "Manufacturer" ""
			(at 396.35 382.652 0)
			(layer "F.Fab")
			(hide yes)
			(effects
				(font
					(size 1 1)
					(thickness 0.15)
				)
			)
		)
		(property ki_fp_filters "Net*Tie*")
		(sheetname "/Supply/")
		(sheetfile "supply.kicad_sch")
		(attr smd exclude_from_pos_files exclude_from_bom)
		(net_tie_pad_groups "1, 2")
		(fp_poly
			(pts
				(xy -0.0635 -0.0635) (xy 0.0625 -0.0635) (xy 0.0625 0.0635) (xy -0.0635 0.0635)
			)
			(stroke
				(width 0)
				(type solid)
			)
			(fill yes)
			(layer "F.Cu")
		)
		(pad "1" smd roundrect
			(at -0.127 0)
			(size 0.127 0.127)
			(layers "F.Cu")
			(roundrect_rratio 0.5)
			(chamfer_ratio 0)
			(chamfer top_left bottom_left)
			(net 145 "/Supply/1V7_SEN_-")
			(pinfunction "1")
			(pintype "passive")
		)
		(pad "2" smd roundrect
			(at 0.126 0 180)
			(size 0.127 0.127)
			(layers "F.Cu")
			(roundrect_rratio 0.5)
			(chamfer_ratio 0)
			(chamfer top_left bottom_left)
			(net 64 "/Supply/1V7")
			(pinfunction "2")
			(pintype "passive")
		)
	)
	(footprint "antmicro-footprints:R_0402_1005Metric"
		(layer "F.Cu")
		(at 196.395501 189.1605 180)
		(descr "Resistor SMD 0402")
		(tags "resistor SMD 0402")
		(property "Reference" "R151"
			(at 3.895501 -0.3395 180)
			(layer "F.SilkS")
			(effects
				(font
					(size 0.7 0.7)
					(thickness 0.15)
				)
				(justify left bottom)
			)
		)
		(property "Value" "R_0R_0402"
			(at -1.011843 1.772047 180)
			(layer "F.Fab")
			(effects
				(font
					(size 0.7 0.7)
					(thickness 0.15)
				)
				(justify left bottom)
			)
		)
		(property "Datasheet" "https://industrial.panasonic.com/cdbs/www-data/pdf/RDA0000/AOA0000C301.pdf"
			(at 0 0 180)
			(layer "F.Fab")
			(hide yes)
			(effects
				(font
					(size 1.27 1.27)
					(thickness 0.15)
				)
			)
		)
		(property "Author" "Antmicro"
			(at 392.791002 378.321 0)
			(layer "F.Fab")
			(hide yes)
			(effects
				(font
					(size 1 1)
					(thickness 0.15)
				)
			)
		)
		(property "Current" "1A"
			(at 392.791002 378.321 0)
			(layer "F.Fab")
			(hide yes)
			(effects
				(font
					(size 1 1)
					(thickness 0.15)
				)
			)
		)
		(property "License" "Apache-2.0"
			(at 392.791002 378.321 0)
			(layer "F.Fab")
			(hide yes)
			(effects
				(font
					(size 1 1)
					(thickness 0.15)
				)
			)
		)
		(property "MPN" "ERJ2GE0R00X"
			(at 392.791002 378.321 0)
			(layer "F.Fab")
			(hide yes)
			(effects
				(font
					(size 1 1)
					(thickness 0.15)
				)
			)
		)
		(property "Manufacturer" "Panasonic"
			(at 392.791002 378.321 0)
			(layer "F.Fab")
			(hide yes)
			(effects
				(font
					(size 1 1)
					(thickness 0.15)
				)
			)
		)
		(property "Tolerance" ""
			(at 392.791002 378.321 0)
			(layer "F.Fab")
			(hide yes)
			(effects
				(font
					(size 1 1)
					(thickness 0.15)
				)
			)
		)
		(property "Val" "0R"
			(at 392.791002 378.321 0)
			(layer "F.Fab")
			(hide yes)
			(effects
				(font
					(size 1 1)
					(thickness 0.15)
				)
			)
		)
		(sheetname "/Supply/")
		(sheetfile "supply.kicad_sch")
		(attr smd)
		(fp_rect
			(start -0.93 -0.47)
			(end 0.93 0.47)
			(stroke
				(width 0.05)
				(type solid)
			)
			(fill no)
			(layer "F.CrtYd")
		)
		(fp_rect
			(start -0.5 -0.25)
			(end 0.5 0.25)
			(stroke
				(width 0.15)
				(type solid)
			)
			(fill no)
			(layer "F.Fab")
		)
		(pad "1" smd roundrect
			(at -0.485 0 180)
			(size 0.59 0.64)
			(layers "F.Cu" "F.Mask" "F.Paste")
			(roundrect_rratio 0.25)
			(net 210 "/Supply/FB1")
			(pintype "passive")
		)
		(pad "2" smd roundrect
			(at 0.485 0 180)
			(size 0.59 0.64)
			(layers "F.Cu" "F.Mask" "F.Paste")
			(roundrect_rratio 0.25)
			(net 42 "/Supply/MGTAVCC_local")
			(pintype "passive")
		)
	)
	(footprint "antmicro-footprints:R_0603_1608Metric"
		(layer "F.Cu")
		(at 190.725 193.3 180)
		(descr "Resistor SMD 0603")
		(tags "resistor SMD 0603")
		(property "Reference" "R183"
			(at 1.375 0.8 180)
			(layer "F.SilkS")
			(effects
				(font
					(size 0.7 0.7)
					(thickness 0.15)
				)
				(justify left bottom)
			)
		)
		(property "Value" "R_0R_22.4A_0603"
			(at 0 1.6 180)
			(layer "F.Fab")
			(effects
				(font
					(size 0.7 0.7)
					(thickness 0.15)
				)
				(justify left bottom)
			)
		)
		(property "Datasheet" "https://fscdn.rohm.com/en/products/databook/datasheet/passive/resistor/chip_resistor/pmr-jpw-e.pdf"
			(at 0 0 180)
			(layer "F.Fab")
			(hide yes)
			(effects
				(font
					(size 1.27 1.27)
					(thickness 0.15)
				)
			)
		)
		(property "Author" "Antmicro"
			(at 381.45 386.6 0)
			(layer "F.Fab")
			(hide yes)
			(effects
				(font
					(size 1 1)
					(thickness 0.15)
				)
			)
		)
		(property "License" "Apache-2.0"
			(at 381.45 386.6 0)
			(layer "F.Fab")
			(hide yes)
			(effects
				(font
					(size 1 1)
					(thickness 0.15)
				)
			)
		)
		(property "MPN" "PMR03EZPJ000"
			(at 381.45 386.6 0)
			(layer "F.Fab")
			(hide yes)
			(effects
				(font
					(size 1 1)
					(thickness 0.15)
				)
			)
		)
		(property "Manufacturer" "ROHM Semiconductor"
			(at 381.45 386.6 0)
			(layer "F.Fab")
			(hide yes)
			(effects
				(font
					(size 1 1)
					(thickness 0.15)
				)
			)
		)
		(property "Max. Curr." "22.4A"
			(at 381.45 386.6 0)
			(layer "F.Fab")
			(hide yes)
			(effects
				(font
					(size 1 1)
					(thickness 0.15)
				)
			)
		)
		(property "Val" "0R"
			(at 381.45 386.6 0)
			(layer "F.Fab")
			(hide yes)
			(effects
				(font
					(size 1 1)
					(thickness 0.15)
				)
			)
		)
		(sheetname "/Supply/")
		(sheetfile "supply.kicad_sch")
		(attr smd)
		(fp_line
			(start -0.3 0.3)
			(end 0.3 0.3)
			(stroke
				(width 0.15)
				(type solid)
			)
			(layer "F.SilkS")
		)
		(fp_line
			(start -0.3 -0.3)
			(end 0.3 -0.3)
			(stroke
				(width 0.15)
				(type solid)
			)
			(layer "F.SilkS")
		)
		(fp_rect
			(start -1.25 -0.7)
			(end 1.25 0.7)
			(stroke
				(width 0.05)
				(type solid)
			)
			(fill no)
			(layer "F.CrtYd")
		)
		(fp_rect
			(start -0.8 -0.4)
			(end 0.8 0.4)
			(stroke
				(width 0.15)
				(type solid)
			)
			(fill no)
			(layer "F.Fab")
		)
		(pad "1" smd roundrect
			(at -0.7 0 180)
			(size 0.6 0.8)
			(layers "F.Cu" "F.Mask" "F.Paste")
			(roundrect_rratio 0.2)
			(net 76 "/Supply/MGTAVTT_OUT")
			(pintype "passive")
		)
		(pad "2" smd roundrect
			(at 0.7 0 180)
			(size 0.6 0.8)
			(layers "F.Cu" "F.Mask" "F.Paste")
			(roundrect_rratio 0.2)
			(net 226 "+1V2_MGTAVTT")
			(pintype "passive")
		)
	)
	(footprint "antmicro-footprints:Oscillator_SMD_Abracon_ASFL1-4Pin_5.0x3.2mm"
		(layer "F.Cu")
		(at 135 191.9)
		(property "Reference" "Y3"
			(at 3 -1.1 0)
			(layer "F.SilkS")
			(effects
				(font
					(size 0.7 0.7)
					(thickness 0.15)
				)
				(justify left bottom)
			)
		)
		(property "Value" "Oscillator_100MHz_ASFL1"
			(at -11.7 3.3 0)
			(layer "F.Fab")
			(effects
				(font
					(size 0.7 0.7)
					(thickness 0.15)
				)
				(justify left bottom)
			)
		)
		(property "Datasheet" "https://abracon.com/Oscillators/ASFL1.pdf"
			(at 0 0 0)
			(layer "F.Fab")
			(hide yes)
			(effects
				(font
					(size 1.27 1.27)
					(thickness 0.15)
				)
			)
		)
		(property "Author" "Antmicro"
			(at 0 0 0)
			(layer "F.Fab")
			(hide yes)
			(effects
				(font
					(size 1 1)
					(thickness 0.15)
				)
			)
		)
		(property "License" "Apache-2.0"
			(at 0 0 0)
			(layer "F.Fab")
			(hide yes)
			(effects
				(font
					(size 1 1)
					(thickness 0.15)
				)
			)
		)
		(property "MPN" "ASFL1-100.000MHZ-L-T"
			(at 0 0 0)
			(layer "F.Fab")
			(hide yes)
			(effects
				(font
					(size 1 1)
					(thickness 0.15)
				)
			)
		)
		(property "Manufacturer" "Abracon"
			(at 0 0 0)
			(layer "F.Fab")
			(hide yes)
			(effects
				(font
					(size 1 1)
					(thickness 0.15)
				)
			)
		)
		(property "Val" "100 MHz"
			(at 0 0 0)
			(layer "F.Fab")
			(hide yes)
			(effects
				(font
					(size 1 1)
					(thickness 0.15)
				)
			)
		)
		(sheetname "/FPGA bank 16/")
		(sheetfile "fpga-bank-16.kicad_sch")
		(attr smd)
		(fp_line
			(start -2.702 -1.801)
			(end -2.301 -1.801)
			(stroke
				(width 0.15)
				(type solid)
			)
			(layer "F.SilkS")
		)
		(fp_line
			(start -2.702 -1.401)
			(end -2.702 -1.801)
			(stroke
				(width 0.15)
				(type solid)
			)
			(layer "F.SilkS")
		)
		(fp_line
			(start -2.702 1.8)
			(end -2.702 1.398)
			(stroke
				(width 0.15)
				(type solid)
			)
			(layer "F.SilkS")
		)
		(fp_line
			(start 2.298 -1.801)
			(end 2.7 -1.801)
			(stroke
				(width 0.15)
				(type solid)
			)
			(layer "F.SilkS")
		)
		(fp_line
			(start 2.7 -1.801)
			(end 2.7 -1.401)
			(stroke
				(width 0.15)
				(type solid)
			)
			(layer "F.SilkS")
		)
		(fp_line
			(start 2.7 1.398)
			(end 2.7 1.8)
			(stroke
				(width 0.15)
				(type solid)
			)
			(layer "F.SilkS")
		)
		(fp_line
			(start 2.7 1.8)
			(end 2.298 1.8)
			(stroke
				(width 0.15)
				(type solid)
			)
			(layer "F.SilkS")
		)
		(fp_circle
			(center -2.4 2.1)
			(end -2.35 2.1)
			(stroke
				(width 0.15)
				(type solid)
			)
			(fill no)
			(layer "F.SilkS")
		)
		(fp_rect
			(start -3 -2.101)
			(end 2.999 2.1)
			(stroke
				(width 0.05)
				(type solid)
			)
			(fill no)
			(layer "F.CrtYd")
		)
		(fp_line
			(start -2.3 1.6)
			(end -2.5 1.4)
			(stroke
				(width 0.15)
				(type solid)
			)
			(layer "F.Fab")
		)
		(fp_line
			(start -2.2 1.6)
			(end -2.5 1.3)
			(stroke
				(width 0.15)
				(type solid)
			)
			(layer "F.Fab")
		)
		(fp_line
			(start -2.1 1.6)
			(end -2.5 1.2)
			(stroke
				(width 0.15)
				(type solid)
			)
			(layer "F.Fab")
		)
		(fp_line
			(start -2 1.6)
			(end -2.5 1.1)
			(stroke
				(width 0.15)
				(type solid)
			)
			(layer "F.Fab")
		)
		(fp_rect
			(start -2.5 -1.601)
			(end 2.499 1.6)
			(stroke
				(width 0.15)
				(type solid)
			)
			(fill no)
			(layer "F.Fab")
		)
		(pad "1" smd rect
			(at -1.27 1.1 180)
			(size 1.7 1.5)
			(layers "F.Cu" "F.Mask" "F.Paste")
			(net 200 "+3V3")
			(pinfunction "EN")
			(pintype "input")
		)
		(pad "2" smd rect
			(at 1.269 1.1)
			(size 1.7 1.5)
			(layers "F.Cu" "F.Mask" "F.Paste")
			(net 1 "GND")
			(pinfunction "GND")
			(pintype "power_in")
		)
		(pad "3" smd rect
			(at 1.269 -1.101)
			(size 1.7 1.5)
			(layers "F.Cu" "F.Mask" "F.Paste")
			(net 706 "/FPGA bank 16/GCLK100")
			(pinfunction "OUT")
			(pintype "output")
		)
		(pad "4" smd rect
			(at -1.27 -1.101)
			(size 1.7 1.5)
			(layers "F.Cu" "F.Mask" "F.Paste")
			(net 200 "+3V3")
			(pinfunction "VDD")
			(pintype "power_in")
		)
	)
)
